# T6G (Grand Teton) — schematic netlist excerpt (pin names and nets, part order shuffled) for the footprints in the layout excerpt that follows; sources: Cadence DE-HDL packaged netlist, KiCad conversion of 04192023_DAF0TMB3IC0_F0TG_MB_C_brd_V02_OCP.brd

R8089  Q_RES  0 5% CHIP  pkg 0402LF  page 104 : A = PWRGD_CHGL_CPU1 ; B = PWRGD_CHGL_CPU1_R1
R79  Q_RES  100K 1% CHIP  pkg 0402LF  page 132 : A = RMII_OCP_BMC_RXD_0 ; B = GND
C666  Q_CAP  100UF 4V 20% X6S  pkg C0805  page 301 : A = P1V8_CPU0_RT2_1A ; B = GND

(kicad_pcb
	(version 20260206)
	(generator "pcbnew")
	(generator_version "10.0")
	(general
		(thickness 1.6)
		(legacy_teardrops no)
	)
	(paper "A4")
	(title_block
		(title "04192023_DAF0TMB3IC0_F0TG_MB_C_brd_V02_OCP.brd")
		(comment 1 "Grand Teton / footprints 3802-3804 of 8354")
	)
	(layers
		(0 "F.Cu" signal "TOP")
		(4 "In1.Cu" signal "GND")
		(6 "In2.Cu" signal "IN1")
		(8 "In3.Cu" signal "GND1")
		(10 "In4.Cu" signal "IN2")
		(12 "In5.Cu" signal "GND2")
		(14 "In6.Cu" signal "IN3")
		(16 "In7.Cu" signal "GND3")
		(18 "In8.Cu" signal "VCC")
		(20 "In9.Cu" signal "VCC1")
		(22 "In10.Cu" signal "GND4")
		(24 "In11.Cu" signal "IN4")
		(26 "In12.Cu" signal "GND5")
		(28 "In13.Cu" signal "IN5")
		(30 "In14.Cu" signal "GND6")
		(32 "In15.Cu" signal "IN6")
		(34 "In16.Cu" signal "GND7")
		(2 "B.Cu" signal "BOTTOM")
		(9 "F.Adhes" user "F.Adhesive")
		(11 "B.Adhes" user "B.Adhesive")
		(13 "F.Paste" user "Package Geometry/Pastemask Top")
		(15 "B.Paste" user "Package Geometry/Pastemask Bottom")
		(5 "F.SilkS" user "Ref Des/Silkscreen Top")
		(7 "B.SilkS" user "Ref Des/Silkscreen Bottom")
		(1 "F.Mask" user "Board Geometry/Soldermask Top")
		(3 "B.Mask" user "Board Geometry/Soldermask Bottom")
		(17 "Dwgs.User" user "User.Drawings")
		(19 "Cmts.User" user "User.Comments")
		(21 "Eco1.User" user "User.Eco1")
		(23 "Eco2.User" user "User.Eco2")
		(25 "Edge.Cuts" user "Board Geometry/Outline")
		(27 "Margin" user)
		(31 "F.CrtYd" user "Package Geometry/Place Bound Top")
		(29 "B.CrtYd" user "Package Geometry/Place Bound Bottom")
		(35 "F.Fab" user "Ref Des/Assembly Top")
		(33 "B.Fab" user "Ref Des/Assembly Bottom")
	)
	(footprint ""
		(layer "F.Cu")
		(at 426.230796 -394.7668)
		(property "Reference" "C666"
			(at 0 0 0)
			(layer "F.SilkS")
			(hide yes)
			(effects
				(font
					(size 1.27 1.27)
				)
			)
		)
		(property "Value" ""
			(at 0 0 0)
			(layer "F.Fab")
			(effects
				(font
					(size 1.27 1.27)
				)
			)
		)
		(duplicate_pad_numbers_are_jumpers no)
		(fp_line
			(start -1.524 -0.762)
			(end 1.524 -0.762)
			(stroke
				(width 0.1524)
				(type default)
			)
			(layer "F.SilkS")
		)
		(fp_line
			(start -1.524 0.762)
			(end -1.524 -0.762)
			(stroke
				(width 0.1524)
				(type default)
			)
			(layer "F.SilkS")
		)
		(fp_line
			(start 1.524 -0.762)
			(end 1.524 0.762)
			(stroke
				(width 0.1524)
				(type default)
			)
			(layer "F.SilkS")
		)
		(fp_line
			(start 1.524 0.762)
			(end -1.524 0.762)
			(stroke
				(width 0.1524)
				(type default)
			)
			(layer "F.SilkS")
		)
		(fp_line
			(start -1.1049 -0.724916)
			(end -1.1049 0.724916)
			(stroke
				(width 0.1)
				(type default)
			)
			(layer "F.Fab")
		)
		(fp_line
			(start -1.1049 0.724916)
			(end 1.1049 0.724916)
			(stroke
				(width 0.1)
				(type default)
			)
			(layer "F.Fab")
		)
		(fp_line
			(start 1.1049 -0.724916)
			(end -1.1049 -0.724916)
			(stroke
				(width 0.1)
				(type default)
			)
			(layer "F.Fab")
		)
		(fp_line
			(start 1.1049 0.724916)
			(end 1.1049 -0.724916)
			(stroke
				(width 0.1)
				(type default)
			)
			(layer "F.Fab")
		)
		(pad "1" smd rect
			(at -0.889 0 180)
			(size 1.016 1.27)
			(layers "F.Cu" "F.Mask" "F.Paste")
			(net "P1V8_CPU0_RT2_1A")
		)
		(pad "2" smd rect
			(at 0.889 0 180)
			(size 1.016 1.27)
			(layers "F.Cu" "F.Mask" "F.Paste")
			(net "GND")
		)
	)
	(footprint ""
		(layer "F.Cu")
		(at 198.247 -92.456)
		(property "Reference" "R8089"
			(at 0 0 0)
			(layer "F.SilkS")
			(hide yes)
			(effects
				(font
					(size 1.27 1.27)
				)
			)
		)
		(property "Value" ""
			(at 0 0 0)
			(layer "F.Fab")
			(effects
				(font
					(size 1.27 1.27)
				)
			)
		)
		(duplicate_pad_numbers_are_jumpers no)
		(fp_line
			(start -0.7874 -0.4064)
			(end 0.7874 -0.4064)
			(stroke
				(width 0.1524)
				(type default)
			)
			(layer "F.SilkS")
		)
		(fp_line
			(start -0.7874 0.4064)
			(end -0.7874 -0.4064)
			(stroke
				(width 0.1524)
				(type default)
			)
			(layer "F.SilkS")
		)
		(fp_line
			(start 0.7874 -0.4064)
			(end 0.7874 0.4064)
			(stroke
				(width 0.1524)
				(type default)
			)
			(layer "F.SilkS")
		)
		(fp_line
			(start 0.7874 0.4064)
			(end -0.7874 0.4064)
			(stroke
				(width 0.1524)
				(type default)
			)
			(layer "F.SilkS")
		)
		(fp_line
			(start -0.67945 -0.305054)
			(end -0.12065 -0.305054)
			(stroke
				(width 0.1)
				(type default)
			)
			(layer "F.Fab")
		)
		(fp_line
			(start -0.67945 0.3048)
			(end -0.67945 -0.305054)
			(stroke
				(width 0.1)
				(type default)
			)
			(layer "F.Fab")
		)
		(fp_line
			(start -0.12065 -0.305054)
			(end -0.12065 -0.2794)
			(stroke
				(width 0.1)
				(type default)
			)
			(layer "F.Fab")
		)
		(fp_line
			(start -0.12065 -0.2794)
			(end 0.12065 -0.2794)
			(stroke
				(width 0.1)
				(type default)
			)
			(layer "F.Fab")
		)
		(fp_line
			(start -0.12065 0.2794)
			(end -0.12065 0.3048)
			(stroke
				(width 0.1)
				(type default)
			)
			(layer "F.Fab")
		)
		(fp_line
			(start -0.12065 0.3048)
			(end -0.67945 0.3048)
			(stroke
				(width 0.1)
				(type default)
			)
			(layer "F.Fab")
		)
		(fp_line
			(start 0.120396 0.2794)
			(end -0.12065 0.2794)
			(stroke
				(width 0.1)
				(type default)
			)
			(layer "F.Fab")
		)
		(fp_line
			(start 0.120396 0.3048)
			(end 0.120396 0.2794)
			(stroke
				(width 0.1)
				(type default)
			)
			(layer "F.Fab")
		)
		(fp_line
			(start 0.12065 -0.3048)
			(end 0.67945 -0.3048)
			(stroke
				(width 0.1)
				(type default)
			)
			(layer "F.Fab")
		)
		(fp_line
			(start 0.12065 -0.2794)
			(end 0.12065 -0.3048)
			(stroke
				(width 0.1)
				(type default)
			)
			(layer "F.Fab")
		)
		(fp_line
			(start 0.67945 -0.3048)
			(end 0.67945 0.3048)
			(stroke
				(width 0.1)
				(type default)
			)
			(layer "F.Fab")
		)
		(fp_line
			(start 0.67945 0.3048)
			(end 0.120396 0.3048)
			(stroke
				(width 0.1)
				(type default)
			)
			(layer "F.Fab")
		)
		(pad "1" smd circle
			(at -0.40005 0)
			(size 0 0)
			(layers "F.Cu" "F.Mask" "F.Paste")
			(net "PWRGD_CHGL_CPU1")
		)
		(pad "2" smd circle
			(at 0.40005 0)
			(size 0 0)
			(layers "F.Cu" "F.Mask" "F.Paste")
			(net "PWRGD_CHGL_CPU1_R1")
		)
	)
	(footprint ""
		(layer "F.Cu")
		(at 196.729858 -77.06614 180)
		(property "Reference" "R79"
			(at 0 0 180)
			(layer "F.SilkS")
			(hide yes)
			(effects
				(font
					(size 1.27 1.27)
				)
			)
		)
		(property "Value" ""
			(at 0 0 180)
			(layer "F.Fab")
			(effects
				(font
					(size 1.27 1.27)
				)
			)
		)
		(duplicate_pad_numbers_are_jumpers no)
		(fp_line
			(start 0.7874 0.4064)
			(end -0.7874 0.4064)
			(stroke
				(width 0.1524)
				(type default)
			)
			(layer "F.SilkS")
		)
		(fp_line
			(start 0.7874 -0.4064)
			(end 0.7874 0.4064)
			(stroke
				(width 0.1524)
				(type default)
			)
			(layer "F.SilkS")
		)
		(fp_line
			(start -0.7874 0.4064)
			(end -0.7874 -0.4064)
			(stroke
				(width 0.1524)
				(type default)
			)
			(layer "F.SilkS")
		)
		(fp_line
			(start -0.7874 -0.4064)
			(end 0.7874 -0.4064)
			(stroke
				(width 0.1524)
				(type default)
			)
			(layer "F.SilkS")
		)
		(fp_line
			(start 0.67945 0.3048)
			(end 0.120396 0.3048)
			(stroke
				(width 0.1)
				(type default)
			)
			(layer "F.Fab")
		)
		(fp_line
			(start 0.67945 -0.3048)
			(end 0.67945 0.3048)
			(stroke
				(width 0.1)
				(type default)
			)
			(layer "F.Fab")
		)
		(fp_line
			(start 0.12065 -0.2794)
			(end 0.12065 -0.3048)
			(stroke
				(width 0.1)
				(type default)
			)
			(layer "F.Fab")
		)
		(fp_line
			(start 0.12065 -0.3048)
			(end 0.67945 -0.3048)
			(stroke
				(width 0.1)
				(type default)
			)
			(layer "F.Fab")
		)
		(fp_line
			(start 0.120396 0.3048)
			(end 0.120396 0.2794)
			(stroke
				(width 0.1)
				(type default)
			)
			(layer "F.Fab")
		)
		(fp_line
			(start 0.120396 0.2794)
			(end -0.12065 0.2794)
			(stroke
				(width 0.1)
				(type default)
			)
			(layer "F.Fab")
		)
		(fp_line
			(start -0.12065 0.3048)
			(end -0.67945 0.3048)
			(stroke
				(width 0.1)
				(type default)
			)
			(layer "F.Fab")
		)
		(fp_line
			(start -0.12065 0.2794)
			(end -0.12065 0.3048)
			(stroke
				(width 0.1)
				(type default)
			)
			(layer "F.Fab")
		)
		(fp_line
			(start -0.12065 -0.2794)
			(end 0.12065 -0.2794)
			(stroke
				(width 0.1)
				(type default)
			)
			(layer "F.Fab")
		)
		(fp_line
			(start -0.12065 -0.305054)
			(end -0.12065 -0.2794)
			(stroke
				(width 0.1)
				(type default)
			)
			(layer "F.Fab")
		)
		(fp_line
			(start -0.67945 0.3048)
			(end -0.67945 -0.305054)
			(stroke
				(width 0.1)
				(type default)
			)
			(layer "F.Fab")
		)
		(fp_line
			(start -0.67945 -0.305054)
			(end -0.12065 -0.305054)
			(stroke
				(width 0.1)
				(type default)
			)
			(layer "F.Fab")
		)
		(pad "1" smd circle
			(at -0.40005 0 180)
			(size 0 0)
			(layers "F.Cu" "F.Mask" "F.Paste")
			(net "RMII_OCP_BMC_RXD_0")
		)
		(pad "2" smd circle
			(at 0.40005 0 180)
			(size 0 0)
			(layers "F.Cu" "F.Mask" "F.Paste")
			(net "GND")
		)
	)
)
